(kicad_pcb
	(version 20260206)
	(generator "pcbnew")
	(generator_version "10.0")
	(general
		(thickness 1.6)
		(legacy_teardrops no)
	)
	(paper "A4")
	(title_block
		(title "panther-plus-userver — 13130-1b_20150205.brd")
		(comment 1 "Honey Badger (Wiwynn) / footprints 864-871 of 1509")
	)
	(layers
		(0 "F.Cu" signal "TOP")
		(4 "In1.Cu" signal "L2")
		(6 "In2.Cu" signal "L3")
		(8 "In3.Cu" signal "L4")
		(10 "In4.Cu" signal "L5")
		(12 "In5.Cu" signal "L6")
		(14 "In6.Cu" signal "L7")
		(16 "In7.Cu" signal "L8")
		(18 "In8.Cu" signal "L9")
		(20 "In9.Cu" signal "L10")
		(22 "In10.Cu" signal "L11")
		(2 "B.Cu" signal "BOTTOM")
		(9 "F.Adhes" user "F.Adhesive")
		(11 "B.Adhes" user "B.Adhesive")
		(13 "F.Paste" user "Package Geometry/Pastemask Top")
		(15 "B.Paste" user "Package Geometry/Pastemask Bottom")
		(5 "F.SilkS" user "Ref Des/Silkscreen Top")
		(7 "B.SilkS" user "Ref Des/Silkscreen Bottom")
		(1 "F.Mask" user "Board Geometry/Soldermask Top")
		(3 "B.Mask" user "Board Geometry/Soldermask Bottom")
		(17 "Dwgs.User" user "User.Drawings")
		(19 "Cmts.User" user "User.Comments")
		(21 "Eco1.User" user "User.Eco1")
		(23 "Eco2.User" user "User.Eco2")
		(25 "Edge.Cuts" user "Board Geometry/Outline")
		(27 "Margin" user)
		(31 "F.CrtYd" user "Package Geometry/Place Bound Top")
		(29 "B.CrtYd" user "Package Geometry/Place Bound Bottom")
		(35 "F.Fab" user "Ref Des/Assembly Top")
		(33 "B.Fab" user "Ref Des/Assembly Bottom")
	)
	(footprint ""
		(layer "B.Cu")
		(at 70.739 -26.8732 180)
		(property "Reference" "R344"
			(at 0 0 0)
			(layer "B.SilkS")
			(hide yes)
			(effects
				(font
					(size 1.27 1.27)
				)
				(justify mirror)
			)
		)
		(property "Value" "10KR2F-2-GP"
			(at -0.064008 -3.993896 180)
			(unlocked yes)
			(layer "B.Fab")
			(hide yes)
			(effects
				(font
					(size 1.016 1.016)
					(thickness 0.1524)
				)
				(justify mirror)
			)
		)
		(property "Device Type" "R402H16"
			(at -0.064008 -5.517896 180)
			(unlocked yes)
			(layer "B.Fab")
			(hide yes)
			(effects
				(font
					(size 1.016 1.016)
					(thickness 0.1524)
				)
				(justify mirror)
			)
		)
		(duplicate_pad_numbers_are_jumpers no)
		(fp_rect
			(start 0.381 0.8382)
			(end -0.381 -0.8382)
			(stroke
				(width 0)
				(type default)
			)
			(fill no)
			(layer "B.CrtYd")
		)
		(fp_rect
			(start 0.381 0.8382)
			(end -0.381 -0.8382)
			(stroke
				(width 0)
				(type default)
			)
			(fill no)
			(layer "B.Fab")
		)
		(pad "1" smd custom
			(at 0 -0.4318)
			(size 0.127 0.127)
			(layers "B.Cu" "B.Mask" "B.Paste")
			(net "P3V3_CPU")
			(options
				(clearance outline)
				(anchor circle)
			)
			(primitives
				(gr_poly
					(pts
						(arc
							(start -0.2032 0.2794)
							(mid -0.239121 0.264521)
							(end -0.254 0.2286)
						)
						(arc
							(start -0.254 -0.2286)
							(mid -0.239121 -0.264521)
							(end -0.2032 -0.2794)
						)
						(arc
							(start 0.2032 -0.2794)
							(mid 0.239121 -0.264521)
							(end 0.254 -0.2286)
						)
						(arc
							(start 0.254 0.2286)
							(mid 0.239121 0.264521)
							(end 0.2032 0.2794)
						)
					)
					(width 0)
					(fill yes)
				)
			)
		)
		(pad "2" smd custom
			(at 0 0.4318)
			(size 0.127 0.127)
			(layers "B.Cu" "B.Mask" "B.Paste")
			(net "GBE_SDP0")
			(options
				(clearance outline)
				(anchor circle)
			)
			(primitives
				(gr_poly
					(pts
						(arc
							(start -0.2032 0.2794)
							(mid -0.239121 0.264521)
							(end -0.254 0.2286)
						)
						(arc
							(start -0.254 -0.2286)
							(mid -0.239121 -0.264521)
							(end -0.2032 -0.2794)
						)
						(arc
							(start 0.2032 -0.2794)
							(mid 0.239121 -0.264521)
							(end 0.254 -0.2286)
						)
						(arc
							(start 0.254 0.2286)
							(mid 0.239121 0.264521)
							(end 0.2032 0.2794)
						)
					)
					(width 0)
					(fill yes)
				)
			)
		)
	)
	(footprint ""
		(layer "B.Cu")
		(at 89.916 -16.383)
		(property "Reference" "C253"
			(at 0 0 0)
			(layer "B.SilkS")
			(hide yes)
			(effects
				(font
					(size 1.27 1.27)
				)
				(justify mirror)
			)
		)
		(property "Value" "SC1U10V2KX-1GP"
			(at -1.1811 -2.7051 0)
			(unlocked yes)
			(layer "B.Fab")
			(hide yes)
			(effects
				(font
					(size 1.016 1.016)
					(thickness 0.1524)
				)
				(justify mirror)
			)
		)
		(property "Device Type" "C402H22"
			(at -1.1811 -4.2291 0)
			(unlocked yes)
			(layer "B.Fab")
			(hide yes)
			(effects
				(font
					(size 1.016 1.016)
					(thickness 0.1524)
				)
				(justify mirror)
			)
		)
		(duplicate_pad_numbers_are_jumpers no)
		(fp_rect
			(start 0.381 0.7366)
			(end -0.381 -0.7366)
			(stroke
				(width 0)
				(type default)
			)
			(fill no)
			(layer "B.CrtYd")
		)
		(fp_rect
			(start 0.381 0.7366)
			(end -0.381 -0.7366)
			(stroke
				(width 0)
				(type default)
			)
			(fill no)
			(layer "B.Fab")
		)
		(pad "1" smd custom
			(at 0 -0.4572 180)
			(size 0.1143 0.1143)
			(layers "B.Cu" "B.Mask" "B.Paste")
			(net "P1V0")
			(options
				(clearance outline)
				(anchor circle)
			)
			(primitives
				(gr_poly
					(pts
						(arc
							(start -0.254 0.1778)
							(mid -0.239121 0.213721)
							(end -0.2032 0.2286)
						)
						(arc
							(start 0.2032 0.2286)
							(mid 0.239121 0.213721)
							(end 0.254 0.1778)
						)
						(arc
							(start 0.254 -0.1778)
							(mid 0.239121 -0.213721)
							(end 0.2032 -0.2286)
						)
						(arc
							(start -0.2032 -0.2286)
							(mid -0.239121 -0.213721)
							(end -0.254 -0.1778)
						)
					)
					(width 0)
					(fill yes)
				)
			)
		)
		(pad "2" smd custom
			(at 0 0.4572 180)
			(size 0.1143 0.1143)
			(layers "B.Cu" "B.Mask" "B.Paste")
			(net "GND")
			(options
				(clearance outline)
				(anchor circle)
			)
			(primitives
				(gr_poly
					(pts
						(arc
							(start -0.254 0.1778)
							(mid -0.239121 0.213721)
							(end -0.2032 0.2286)
						)
						(arc
							(start 0.2032 0.2286)
							(mid 0.239121 0.213721)
							(end 0.254 0.1778)
						)
						(arc
							(start 0.254 -0.1778)
							(mid 0.239121 -0.213721)
							(end 0.2032 -0.2286)
						)
						(arc
							(start -0.2032 -0.2286)
							(mid -0.239121 -0.213721)
							(end -0.254 -0.1778)
						)
					)
					(width 0)
					(fill yes)
				)
			)
		)
	)
	(footprint ""
		(layer "B.Cu")
		(at 96.012 -19.685 90)
		(property "Reference" "C252"
			(at 0 0 90)
			(layer "B.SilkS")
			(hide yes)
			(effects
				(font
					(size 1.27 1.27)
				)
				(justify mirror)
			)
		)
		(property "Value" "SC1U10V2KX-1GP"
			(at -1.1811 -2.7051 90)
			(unlocked yes)
			(layer "B.Fab")
			(hide yes)
			(effects
				(font
					(size 1.016 1.016)
					(thickness 0.1524)
				)
				(justify mirror)
			)
		)
		(property "Device Type" "C402H22"
			(at -1.1811 -4.2291 90)
			(unlocked yes)
			(layer "B.Fab")
			(hide yes)
			(effects
				(font
					(size 1.016 1.016)
					(thickness 0.1524)
				)
				(justify mirror)
			)
		)
		(duplicate_pad_numbers_are_jumpers no)
		(fp_rect
			(start 0.381 0.7366)
			(end -0.381 -0.7366)
			(stroke
				(width 0)
				(type default)
			)
			(fill no)
			(layer "B.CrtYd")
		)
		(fp_rect
			(start 0.381 0.7366)
			(end -0.381 -0.7366)
			(stroke
				(width 0)
				(type default)
			)
			(fill no)
			(layer "B.Fab")
		)
		(pad "1" smd custom
			(at 0 -0.4572 270)
			(size 0.1143 0.1143)
			(layers "B.Cu" "B.Mask" "B.Paste")
			(net "VCCA_PLLDDR1_AVN")
			(options
				(clearance outline)
				(anchor circle)
			)
			(primitives
				(gr_poly
					(pts
						(arc
							(start -0.254 0.1778)
							(mid -0.239121 0.213721)
							(end -0.2032 0.2286)
						)
						(arc
							(start 0.2032 0.2286)
							(mid 0.239121 0.213721)
							(end 0.254 0.1778)
						)
						(arc
							(start 0.254 -0.1778)
							(mid 0.239121 -0.213721)
							(end 0.2032 -0.2286)
						)
						(arc
							(start -0.2032 -0.2286)
							(mid -0.239121 -0.213721)
							(end -0.254 -0.1778)
						)
					)
					(width 0)
					(fill yes)
				)
			)
		)
		(pad "2" smd custom
			(at 0 0.4572 270)
			(size 0.1143 0.1143)
			(layers "B.Cu" "B.Mask" "B.Paste")
			(net "GND")
			(options
				(clearance outline)
				(anchor circle)
			)
			(primitives
				(gr_poly
					(pts
						(arc
							(start -0.254 0.1778)
							(mid -0.239121 0.213721)
							(end -0.2032 0.2286)
						)
						(arc
							(start 0.2032 0.2286)
							(mid 0.239121 0.213721)
							(end 0.254 0.1778)
						)
						(arc
							(start 0.254 -0.1778)
							(mid 0.239121 -0.213721)
							(end 0.2032 -0.2286)
						)
						(arc
							(start -0.2032 -0.2286)
							(mid -0.239121 -0.213721)
							(end -0.254 -0.1778)
						)
					)
					(width 0)
					(fill yes)
				)
			)
		)
	)
	(footprint ""
		(layer "B.Cu")
		(at 40.005 -40.005 90)
		(property "Reference" "L13"
			(at 0 0 90)
			(layer "B.SilkS")
			(hide yes)
			(effects
				(font
					(size 1.27 1.27)
				)
				(justify mirror)
			)
		)
		(property "Value" "BLM18PG330SN1D-GP"
			(at 0.0254 -2.0193 90)
			(unlocked yes)
			(layer "B.Fab")
			(hide yes)
			(effects
				(font
					(size 1.016 1.016)
					(thickness 0.1524)
				)
				(justify mirror)
			)
		)
		(property "Device Type" "L1608-UH38"
			(at 0.0254 -3.5433 90)
			(unlocked yes)
			(layer "B.Fab")
			(hide yes)
			(effects
				(font
					(size 1.016 1.016)
					(thickness 0.1524)
				)
				(justify mirror)
			)
		)
		(duplicate_pad_numbers_are_jumpers no)
		(fp_line
			(start 0.4064 0)
			(end -0.4064 0)
			(stroke
				(width 0.2032)
				(type default)
			)
			(layer "B.SilkS")
		)
		(fp_rect
			(start 0.635 1.1811)
			(end -0.635 -1.1811)
			(stroke
				(width 0)
				(type default)
			)
			(fill no)
			(layer "B.CrtYd")
		)
		(fp_rect
			(start 0.635 1.1811)
			(end -0.635 -1.1811)
			(stroke
				(width 0)
				(type default)
			)
			(fill no)
			(layer "B.Fab")
		)
		(pad "1" smd custom
			(at 0 -0.6604 270)
			(size 0.19685 0.19685)
			(layers "B.Cu" "B.Mask" "B.Paste")
			(net "P1V5_STBY")
			(options
				(clearance outline)
				(anchor circle)
			)
			(primitives
				(gr_poly
					(pts
						(arc
							(start 0.508 0.2921)
							(mid 0.478242 0.363942)
							(end 0.4064 0.3937)
						)
						(arc
							(start -0.4064 0.3937)
							(mid -0.478242 0.363942)
							(end -0.508 0.2921)
						)
						(arc
							(start -0.508 -0.2921)
							(mid -0.478242 -0.363942)
							(end -0.4064 -0.3937)
						)
						(arc
							(start 0.4064 -0.3937)
							(mid 0.478242 -0.363942)
							(end 0.508 -0.2921)
						)
					)
					(width 0)
					(fill yes)
				)
			)
		)
		(pad "2" smd custom
			(at 0 0.6604 270)
			(size 0.19685 0.19685)
			(layers "B.Cu" "B.Mask" "B.Paste")
			(net "P1V5_CLK_VDDDIF")
			(options
				(clearance outline)
				(anchor circle)
			)
			(primitives
				(gr_poly
					(pts
						(arc
							(start 0.508 0.2921)
							(mid 0.478242 0.363942)
							(end 0.4064 0.3937)
						)
						(arc
							(start -0.4064 0.3937)
							(mid -0.478242 0.363942)
							(end -0.508 0.2921)
						)
						(arc
							(start -0.508 -0.2921)
							(mid -0.478242 -0.363942)
							(end -0.4064 -0.3937)
						)
						(arc
							(start 0.4064 -0.3937)
							(mid 0.478242 -0.363942)
							(end 0.508 -0.2921)
						)
					)
					(width 0)
					(fill yes)
				)
			)
		)
	)
	(footprint ""
		(layer "B.Cu")
		(at 103.124 -67.31)
		(property "Reference" "PC4"
			(at 0 0 0)
			(layer "B.SilkS")
			(hide yes)
			(effects
				(font
					(size 1.27 1.27)
				)
				(justify mirror)
			)
		)
		(property "Value" "SC15P50V2GN-GP"
			(at -1.1811 -2.7051 0)
			(unlocked yes)
			(layer "B.Fab")
			(hide yes)
			(effects
				(font
					(size 1.016 1.016)
					(thickness 0.1524)
				)
				(justify mirror)
			)
		)
		(property "Device Type" "C402H22"
			(at -1.1811 -4.2291 0)
			(unlocked yes)
			(layer "B.Fab")
			(hide yes)
			(effects
				(font
					(size 1.016 1.016)
					(thickness 0.1524)
				)
				(justify mirror)
			)
		)
		(duplicate_pad_numbers_are_jumpers no)
		(fp_rect
			(start 0.381 0.7366)
			(end -0.381 -0.7366)
			(stroke
				(width 0)
				(type default)
			)
			(fill no)
			(layer "B.CrtYd")
		)
		(fp_rect
			(start 0.381 0.7366)
			(end -0.381 -0.7366)
			(stroke
				(width 0)
				(type default)
			)
			(fill no)
			(layer "B.Fab")
		)
		(pad "1" smd custom
			(at 0 -0.4572 180)
			(size 0.1143 0.1143)
			(layers "B.Cu" "B.Mask" "B.Paste")
			(net "VR_P1V1_VFBR")
			(options
				(clearance outline)
				(anchor circle)
			)
			(primitives
				(gr_poly
					(pts
						(arc
							(start -0.254 0.1778)
							(mid -0.239121 0.213721)
							(end -0.2032 0.2286)
						)
						(arc
							(start 0.2032 0.2286)
							(mid 0.239121 0.213721)
							(end 0.254 0.1778)
						)
						(arc
							(start 0.254 -0.1778)
							(mid 0.239121 -0.213721)
							(end 0.2032 -0.2286)
						)
						(arc
							(start -0.2032 -0.2286)
							(mid -0.239121 -0.213721)
							(end -0.254 -0.1778)
						)
					)
					(width 0)
					(fill yes)
				)
			)
		)
		(pad "2" smd custom
			(at 0 0.4572 180)
			(size 0.1143 0.1143)
			(layers "B.Cu" "B.Mask" "B.Paste")
			(net "VR_P1V1_VFB")
			(options
				(clearance outline)
				(anchor circle)
			)
			(primitives
				(gr_poly
					(pts
						(arc
							(start -0.254 0.1778)
							(mid -0.239121 0.213721)
							(end -0.2032 0.2286)
						)
						(arc
							(start 0.2032 0.2286)
							(mid 0.239121 0.213721)
							(end 0.254 0.1778)
						)
						(arc
							(start 0.254 -0.1778)
							(mid 0.239121 -0.213721)
							(end 0.2032 -0.2286)
						)
						(arc
							(start -0.2032 -0.2286)
							(mid -0.239121 -0.213721)
							(end -0.254 -0.1778)
						)
					)
					(width 0)
					(fill yes)
				)
			)
		)
	)
	(footprint ""
		(layer "B.Cu")
		(at 75.565 -30.1244)
		(property "Reference" "TP49"
			(at 0 0 0)
			(layer "B.SilkS")
			(hide yes)
			(effects
				(font
					(size 1.27 1.27)
				)
				(justify mirror)
			)
		)
		(property "Value" "TPAD24"
			(at 0 -2.9972 0)
			(unlocked yes)
			(layer "B.Fab")
			(hide yes)
			(effects
				(font
					(size 1.016 1.016)
					(thickness 0.1524)
				)
				(justify mirror)
			)
		)
		(property "Device Type" "TPAD24"
			(at 0 -4.5212 0)
			(unlocked yes)
			(layer "B.Fab")
			(hide yes)
			(effects
				(font
					(size 1.016 1.016)
					(thickness 0.1524)
				)
				(justify mirror)
			)
		)
		(duplicate_pad_numbers_are_jumpers no)
		(fp_poly
			(pts
				(arc
					(start 0.3048 0)
					(mid -0.3048 0)
					(end 0.3048 0)
				)
			)
			(stroke
				(width 0)
				(type default)
			)
			(fill no)
			(layer "B.CrtYd")
		)
		(fp_poly
			(pts
				(arc
					(start 0.6096 0)
					(mid -0.6096 0)
					(end 0.6096 0)
				)
			)
			(stroke
				(width 0)
				(type default)
			)
			(fill no)
			(layer "B.Fab")
		)
		(pad "1" smd circle
			(at 0 0 180)
			(size 0.6096 0.6096)
			(layers "B.Cu" "B.Mask" "B.Paste")
			(net "GBE_MDIO_CLK0")
		)
	)
	(footprint ""
		(layer "B.Cu")
		(at 80.01 -26.289 -90)
		(property "Reference" "R408"
			(at 0 0 90)
			(layer "B.SilkS")
			(hide yes)
			(effects
				(font
					(size 1.27 1.27)
				)
				(justify mirror)
			)
		)
		(property "Value" "4K7R2F-GP"
			(at -1.7907 -1.1176 270)
			(unlocked yes)
			(layer "B.Fab")
			(hide yes)
			(effects
				(font
					(size 1.016 1.016)
					(thickness 0.1524)
				)
				(justify mirror)
			)
		)
		(property "Device Type" "R402H16"
			(at -1.7907 -2.6416 270)
			(unlocked yes)
			(layer "B.Fab")
			(hide yes)
			(effects
				(font
					(size 1.016 1.016)
					(thickness 0.1524)
				)
				(justify mirror)
			)
		)
		(duplicate_pad_numbers_are_jumpers no)
		(fp_rect
			(start 0.381 0.8382)
			(end -0.381 -0.8382)
			(stroke
				(width 0)
				(type default)
			)
			(fill no)
			(layer "B.CrtYd")
		)
		(fp_rect
			(start 0.381 0.8382)
			(end -0.381 -0.8382)
			(stroke
				(width 0)
				(type default)
			)
			(fill no)
			(layer "B.Fab")
		)
		(pad "1" smd custom
			(at 0 -0.4318 90)
			(size 0.127 0.127)
			(layers "B.Cu" "B.Mask" "B.Paste")
			(net "P3V3_CPU")
			(options
				(clearance outline)
				(anchor circle)
			)
			(primitives
				(gr_poly
					(pts
						(arc
							(start -0.2032 0.2794)
							(mid -0.239121 0.264521)
							(end -0.254 0.2286)
						)
						(arc
							(start -0.254 -0.2286)
							(mid -0.239121 -0.264521)
							(end -0.2032 -0.2794)
						)
						(arc
							(start 0.2032 -0.2794)
							(mid 0.239121 -0.264521)
							(end 0.254 -0.2286)
						)
						(arc
							(start 0.254 0.2286)
							(mid 0.239121 0.264521)
							(end 0.2032 0.2794)
						)
					)
					(width 0)
					(fill yes)
				)
			)
		)
		(pad "2" smd custom
			(at 0 0.4318 90)
			(size 0.127 0.127)
			(layers "B.Cu" "B.Mask" "B.Paste")
			(net "NGFF_PRESENT_R#")
			(options
				(clearance outline)
				(anchor circle)
			)
			(primitives
				(gr_poly
					(pts
						(arc
							(start -0.2032 0.2794)
							(mid -0.239121 0.264521)
							(end -0.254 0.2286)
						)
						(arc
							(start -0.254 -0.2286)
							(mid -0.239121 -0.264521)
							(end -0.2032 -0.2794)
						)
						(arc
							(start 0.2032 -0.2794)
							(mid 0.239121 -0.264521)
							(end 0.254 -0.2286)
						)
						(arc
							(start 0.254 0.2286)
							(mid 0.239121 0.264521)
							(end 0.2032 0.2794)
						)
					)
					(width 0)
					(fill yes)
				)
			)
		)
	)
	(footprint ""
		(layer "B.Cu")
		(at 89.154 -25.527 -90)
		(property "Reference" "C151"
			(at 0 0 90)
			(layer "B.SilkS")
			(hide yes)
			(effects
				(font
					(size 1.27 1.27)
				)
				(justify mirror)
			)
		)
		(property "Value" "SC1U10V2KX-1GP"
			(at -1.1811 -2.7051 270)
			(unlocked yes)
			(layer "B.Fab")
			(hide yes)
			(effects
				(font
					(size 1.016 1.016)
					(thickness 0.1524)
				)
				(justify mirror)
			)
		)
		(property "Device Type" "C402H22"
			(at -1.1811 -4.2291 270)
			(unlocked yes)
			(layer "B.Fab")
			(hide yes)
			(effects
				(font
					(size 1.016 1.016)
					(thickness 0.1524)
				)
				(justify mirror)
			)
		)
		(duplicate_pad_numbers_are_jumpers no)
		(fp_rect
			(start 0.381 0.7366)
			(end -0.381 -0.7366)
			(stroke
				(width 0)
				(type default)
			)
			(fill no)
			(layer "B.CrtYd")
		)
		(fp_rect
			(start 0.381 0.7366)
			(end -0.381 -0.7366)
			(stroke
				(width 0)
				(type default)
			)
			(fill no)
			(layer "B.Fab")
		)
		(pad "1" smd custom
			(at 0 -0.4572 90)
			(size 0.1143 0.1143)
			(layers "B.Cu" "B.Mask" "B.Paste")
			(net "P1V0")
			(options
				(clearance outline)
				(anchor circle)
			)
			(primitives
				(gr_poly
					(pts
						(arc
							(start -0.254 0.1778)
							(mid -0.239121 0.213721)
							(end -0.2032 0.2286)
						)
						(arc
							(start 0.2032 0.2286)
							(mid 0.239121 0.213721)
							(end 0.254 0.1778)
						)
						(arc
							(start 0.254 -0.1778)
							(mid 0.239121 -0.213721)
							(end 0.2032 -0.2286)
						)
						(arc
							(start -0.2032 -0.2286)
							(mid -0.239121 -0.213721)
							(end -0.254 -0.1778)
						)
					)
					(width 0)
					(fill yes)
				)
			)
		)
		(pad "2" smd custom
			(at 0 0.4572 90)
			(size 0.1143 0.1143)
			(layers "B.Cu" "B.Mask" "B.Paste")
			(net "GND")
			(options
				(clearance outline)
				(anchor circle)
			)
			(primitives
				(gr_poly
					(pts
						(arc
							(start -0.254 0.1778)
							(mid -0.239121 0.213721)
							(end -0.2032 0.2286)
						)
						(arc
							(start 0.2032 0.2286)
							(mid 0.239121 0.213721)
							(end 0.254 0.1778)
						)
						(arc
							(start 0.254 -0.1778)
							(mid 0.239121 -0.213721)
							(end 0.2032 -0.2286)
						)
						(arc
							(start -0.2032 -0.2286)
							(mid -0.239121 -0.213721)
							(end -0.254 -0.1778)
						)
					)
					(width 0)
					(fill yes)
				)
			)
		)
	)
)
